;LEADER: 12 
;HEADER: 
;CODE  : ASCII 
;FILE  : 9048_F0T_Management_Board_D_brd_V04_1213_1625-1-12.drl for  ... layers TOP and BOTTOM
;DESIGN: 9048_F0T_Management_Board_D_brd_V04_1213_1625.brd
;   Holesize 1. = 9.840000 Tolerance = +2.000000/-2.000000 PLATED MILS Quantity = 64
;   Holesize 2. = 10.000000 Tolerance = +0.000000/-10.000000 PLATED MILS Quantity = 2889
;   Holesize 3. = 28.000000 Tolerance = +2.000000/-2.000000 PLATED MILS Quantity = 9
;   Holesize 4. = 32.000000 Tolerance = +4.000000/-0.000000 PLATED MILS Quantity = 2
;   Holesize 5. = 32.000000 Tolerance = +6.000000/-0.000000 PLATED MILS Quantity = 8
;   Holesize 6. = 41.000000 Tolerance = +3.000000/-3.000000 PLATED MILS Quantity = 16
;   Holesize 7. = 67.000000 Tolerance = +3.000000/-3.000000 PLATED MILS Quantity = 18
;   Holesize 8. = 91.000000 Tolerance = +3.000000/-3.000000 PLATED MILS Quantity = 2
;   Holesize 9. = 124.000000 Tolerance = +3.000000/-3.000000 PLATED MILS Quantity = 2
;   Holesize 10. = 126.000000 Tolerance = +3.000000/-3.000000 PLATED MILS Quantity = 2
;   Holesize 11. = 134.000000 Tolerance = +3.000000/-3.000000 PLATED MILS Quantity = 2
;   Holesize 12. = 150.000000 Tolerance = +3.000000/-3.000000 PLATED MILS Quantity = 1
;   Holesize 13. = 36.000000 Tolerance = +2.000000/-2.000000 NON_PLATED MILS Quantity = 6
;   Holesize 14. = 41.000000 Tolerance = +2.000000/-2.000000 NON_PLATED MILS Quantity = 64
;   Holesize 15. = 48.000000 Tolerance = +1.960000/-1.960000 NON_PLATED MILS Quantity = 1
;   Holesize 16. = 67.000000 Tolerance = +1.960000/-1.960000 NON_PLATED MILS Quantity = 1
;   Holesize 17. = 125.000000 Tolerance = +2.000000/-0.000000 NON_PLATED MILS Quantity = 2
%
G90
X0441000Y-0454000
X0441000Y-0444000
X0441000Y-0355000
X0441000Y-0345000
X0441000Y-0333400
X0441000Y-0323400
X0441000Y-0245000
X0441000Y-0235000
X0441000Y-0215000
X0441000Y-0225000
X0441000Y-0126600
X0441000Y-0136600
X0441000Y-0107000
X0441000Y-0117000
X0441000Y-0008000
X0441000Y-0018000
X0441000Y0002000
X0441000Y0012000
X0441000Y0096000
X0441000Y0106000
X0441000Y0116000
X0441000Y0126000
X0441000Y0200000
X0441000Y0210000
X0441000Y0230000
X0441000Y0220000
X0441000Y0304000
X0441000Y0314000
X0441000Y0336000
X0441000Y0326000
X0441000Y0430000
X0441000Y0420000
X0451000Y0420000
X0451000Y0430000
X0451000Y0314000
X0451000Y0326000
X0451000Y0336000
X0451000Y0210000
X0451000Y0220000
X0451000Y0230000
X0451000Y0304000
X0451000Y0126000
X0451000Y0116000
X0451000Y0200000
X0451000Y0012000
X0451000Y0106000
X0451000Y0096000
X0451000Y-0018000
X0451000Y-0008000
X0451000Y0002000
X0451000Y-0136600
X0451000Y-0126600
X0451000Y-0117000
X0451000Y-0107000
X0451000Y-0235000
X0451000Y-0245000
X0451000Y-0225000
X0451000Y-0215000
X0451000Y-0345000
X0451000Y-0355000
X0451000Y-0323400
X0451000Y-0333400
X0451000Y-0444000
X0451000Y-0454000
M00
X0042218Y0003000
X0022218Y0003000
X0003000Y0008494
X0045001Y0095144
X0045500Y0092500
X0012500Y0102000
X0040340Y0100710
X0050710Y0054724
X0035304Y0058317
X0045500Y0041500
X0019200Y0102700
X0043926Y0062248
X0050508Y0057459
X0009407Y0010554
X0027323Y0025842
X0035044Y0035751
X0003000Y0108494
X0003000Y0088494
X0003000Y0068494
X0003000Y0048494
X0003000Y0028494
X0012900Y0105500
X0045276Y0098488
X0040940Y0112559
X0031890Y0110400
X0047948Y0201000
X0019100Y0187420
X0039408Y0195990
X0049236Y0130758
X0049236Y0127758
X0040736Y0130758
X0040736Y0127758
X0032236Y0130758
X0032236Y0127758
X0023736Y0130758
X0023736Y0127758
X0025200Y0116300
X0048500Y0112559
X0003000Y0208494
X0003000Y0188494
X0003000Y0168494
X0003000Y0148494
X0003000Y0128494
X0038300Y0109200
X0031920Y0186610
X0021250Y0206220
X0047294Y0184491
X0049223Y0121291
X0049223Y0123791
X0040723Y0120791
X0040723Y0123791
X0032223Y0120791
X0032223Y0123791
X0023723Y0120791
X0023723Y0123791
X0048940Y0204871
X0048035Y0191535
X0037823Y0198346
X0037360Y0194050
X0036599Y0189016
X0016626Y0193048
X0019129Y0193048
X0016626Y0204248
X0019129Y0201448
X0019129Y0195848
X0019129Y0198648
X0016626Y0201448
X0016626Y0195848
X0016626Y0198648
X0017000Y0208017
X0019129Y0204248
X0050567Y0238630
X0035700Y0218000
X0049700Y0242900
X0041100Y0248900
X0039800Y0213800
X0037485Y0258807
X0024705Y0258767
X0039900Y0211000
X0035600Y0238200
X0035600Y0241200
X0050700Y0250400
X0048023Y0217860
X0046220Y0277170
X0048059Y0214825
X0017065Y0255712
X0030638Y0301213
X0022237Y0301237
X0030638Y0304602
X0022237Y0304626
X0013736Y0299891
X0013736Y0303280
X0047440Y0301336
X0039039Y0301299
X0047440Y0304225
X0039039Y0304278
X0018422Y0227168
X0018422Y0224568
X0021000Y0224500
X0021000Y0227000
X0015922Y0227168
X0015922Y0224568
X0044149Y0224732
X0041993Y0220332
X0039493Y0220332
X0044149Y0227332
X0041993Y0222932
X0039493Y0222932
X0003000Y0308494
X0003000Y0288494
X0003000Y0268494
X0003000Y0248494
X0003000Y0228494
X0018000Y0237900
X0018000Y0240900
X0018000Y0243900
X0018000Y0246900
X0018000Y0249900
X0040500Y0236900
X0024690Y0249267
X0021035Y0249937
X0021135Y0246837
X0024690Y0251967
X0024690Y0246467
X0021135Y0243737
X0021135Y0240667
X0021205Y0232767
X0021135Y0236587
X0041574Y0255937
X0039567Y0243133
X0015688Y0259063
X0017000Y0219288
X0017000Y0215713
X0047714Y0212227
X0017000Y0211541
X0032700Y0395381
X0044330Y0401450
X0031000Y0342500
X0014000Y0404200
X0044341Y0406480
X0014000Y0406700
X0014000Y0401700
X0044500Y0351600
X0044500Y0380000
X0035100Y0352400
X0043500Y0317100
X0044525Y0360000
X0031300Y0329900
X0047075Y0391730
X0038560Y0329739
X0044481Y0328760
X0037020Y0385600
X0044525Y0376000
X0036200Y0368400
X0044500Y0348000
X0037300Y0375000
X0044500Y0344000
X0044525Y0368000
X0044525Y0364000
X0013869Y0352239
X0023810Y0322534
X0044220Y0341008
X0044525Y0384000
X0039100Y0321600
X0035500Y0335000
X0033000Y0318700
X0037800Y0371225
X0037067Y0398337
X0036911Y0394915
X0035900Y0363025
X0031600Y0379600
X0037400Y0359900
X0026300Y0374400
X0035101Y0381610
X0044525Y0324000
X0044525Y0391650
X0044525Y0394150
X0035500Y0340500
X0037735Y0391200
X0044525Y0387800
X0044490Y0397850
X0037875Y0377925
X0044200Y0332000
X0030700Y0315500
X0044500Y0355500
X0003000Y0402126
X0003000Y0382126
X0003000Y0362126
X0003000Y0342126
X0013827Y0325310
X0034300Y0375000
X0033100Y0392100
X0023535Y0329990
X0032000Y0326300
X0025811Y0319400
X0038200Y0364855
X0008300Y0314700
X0030638Y0309068
X0030638Y0311957
X0022237Y0308592
X0022237Y0311481
X0006200Y0312900
X0047440Y0312080
X0039039Y0311933
X0039039Y0309044
X0047440Y0308691
X0048420Y0321616
X0046100Y0422800
X0045100Y0435800
X0032100Y0432800
X0048050Y0436350
X0038000Y0428800
X0046100Y0412700
X0031500Y0428500
X0023677Y0422419
X0029400Y0430900
X0014700Y0425000
X0014600Y0422500
X0042200Y0435900
X0025202Y0425329
X0042900Y0412900
X0043600Y0422800
X0039530Y0409100
X0041200Y0429100
X0017700Y0427600
X0020600Y0428900
X0040848Y0448440
X0022692Y0466518
X0020225Y0447671
X0003000Y0442126
X0003000Y0422126
X0036600Y0408600
X0112796Y0412490
X0125930Y0433110
X0069700Y0408800
X0067000Y0408800
X0081552Y0409660
X0096030Y0409400
X0056500Y0447600
X0123170Y0433200
X0073976Y0408665
X0054100Y0448600
X0052750Y0424200
X0056250Y0424200
X0063569Y0453344
X0063569Y0456844
X0052330Y0413350
X0089700Y0437900
X0079600Y0426400
X0077600Y0431400
X0056482Y0453344
X0056482Y0456844
X0108500Y0408680
X0092500Y0408630
X0103900Y0447640
X0088565Y0426535
X0075650Y0424199
X0072150Y0424199
X0064122Y0431273
X0060622Y0431273
X0108336Y0411547
X0122498Y0419675
X0138750Y0454500
X0138750Y0451500
X0121700Y0424005
X0074782Y0413800
X0116632Y0411500
X0084801Y0409760
X0134300Y0416414
X0095845Y0424755
X0063200Y0408600
X0087800Y0410300
X0072800Y0437900
X0099370Y0445483
X0095870Y0445483
X0096301Y0452793
X0092801Y0452793
X0103461Y0425875
X0104112Y0422946
X0108701Y0418300
X0113000Y0416200
X0112800Y0421600
X0133572Y0423935
X0138987Y0423935
X0133070Y0420874
X0111510Y0434710
X0093259Y0424200
X0129135Y0410250
X0066319Y0413492
X0132070Y0433110
X0133500Y0409110
X0069139Y0413452
X0092870Y0437831
X0095770Y0437920
X0140600Y0412300
X0143000Y0414600
X0100457Y0409100
X0124500Y0424005
X0058620Y0408779
X0085490Y0448085
X0081990Y0448085
X0105500Y0418200
X0135350Y0433016
X0128866Y0433066
X0119500Y0433600
X0077592Y0413437
X0148041Y0426700
X0059511Y0424477
X0071200Y0431700
X0109048Y0425853
X0106700Y0447730
X0077860Y0408678
X0148100Y0433400
X0136230Y0423935
X0068100Y0425400
X0150000Y0414750
X0139700Y0415100
X0119791Y0412301
X0098100Y0412400
X0087600Y0414500
X0149600Y0410500
X0148060Y0423500
X0069030Y0422653
X0079010Y0445750
X0145365Y0426050
X0062600Y0450700
X0056482Y0450344
X0069057Y0419700
X0106083Y0458275
X0098996Y0458275
X0091909Y0458275
X0056476Y0460100
X0063563Y0460100
X0076770Y0426543
X0071035Y0426543
X0051535Y0426544
X0057470Y0426544
X0129900Y0415583
X0059097Y0433502
X0066297Y0433002
X0146600Y0410600
X0095280Y0412500
X0103400Y0420000
X0078800Y0423800
X0138500Y0457250
X0084823Y0460100
X0077500Y0460100
X0070650Y0460100
X0085276Y0445550
X0082256Y0445577
X0100225Y0443127
X0094560Y0443287
X0097156Y0450437
X0092001Y0450402
X0149041Y0458750
X0084320Y0430510
X0132700Y0402700
X0087617Y0359023
X0100215Y0349574
X0100253Y0346387
X0111460Y0361770
X0093916Y0355873
X0129800Y0325800
X0115600Y0337900
X0060600Y0318000
X0060613Y0312012
X0119026Y0393332
X0150820Y0387325
X0089210Y0394175
X0090766Y0384182
X0090766Y0387332
X0090766Y0390481
X0087617Y0377883
X0092360Y0394175
X0093916Y0387332
X0090766Y0381033
X0093916Y0381033
X0138700Y0376600
X0100215Y0355873
X0090766Y0365322
X0090766Y0371584
X0100215Y0381033
X0076500Y0325500
X0097066Y0384182
X0071906Y0384182
X0087617Y0374733
X0081355Y0374733
X0071869Y0381033
X0071906Y0387332
X0078206Y0371584
X0078206Y0365322
X0068757Y0355873
X0087617Y0362173
X0081355Y0362173
X0097066Y0352724
X0071906Y0352724
X0075056Y0355873
X0078206Y0349574
X0087617Y0387332
X0078206Y0377883
X0081355Y0381033
X0087617Y0390481
X0090766Y0377883
X0087617Y0384182
X0081355Y0346425
X0141000Y0358500
X0086481Y0407871
X0071906Y0359023
X0093916Y0384182
X0149500Y0356700
X0124935Y0324900
X0124300Y0348800
X0052820Y0325200
X0097066Y0387332
X0093288Y0330289
X0123100Y0390600
X0142511Y0393690
X0139200Y0372510
X0145703Y0370700
X0126340Y0382700
X0081355Y0349574
X0081700Y0342600
X0094400Y0311100
X0077500Y0316100
X0073400Y0313700
X0068757Y0359023
X0071906Y0362173
X0056600Y0318000
X0131540Y0394690
X0068757Y0362173
X0068719Y0381033
X0081355Y0384182
X0065607Y0384182
X0079000Y0395500
X0081355Y0387332
X0124100Y0311100
X0065607Y0355873
X0097800Y0325700
X0065607Y0374733
X0078206Y0355873
X0068757Y0374733
X0110900Y0378500
X0071906Y0374733
X0149000Y0383070
X0052475Y0364000
X0065607Y0359023
X0114700Y0348500
X0100215Y0387332
X0098300Y0407600
X0120200Y0361600
X0065607Y0352724
X0062458Y0343275
X0075056Y0374733
X0111869Y0365454
X0090766Y0359023
X0122330Y0364670
X0058564Y0354280
X0062458Y0355873
X0071700Y0340600
X0068757Y0371584
X0106514Y0349574
X0087617Y0355873
X0075056Y0349574
X0106515Y0352724
X0090766Y0355873
X0075056Y0352724
X0078206Y0359023
X0068757Y0346425
X0081900Y0337100
X0075056Y0346425
X0122600Y0394600
X0071906Y0377883
X0065607Y0381033
X0150900Y0360325
X0097066Y0349574
X0068757Y0365322
X0071906Y0365322
X0124350Y0352450
X0136000Y0341000
X0111330Y0357800
X0078206Y0381033
X0068757Y0349574
X0087617Y0349574
X0090766Y0352724
X0103180Y0336286
X0075056Y0365322
X0055294Y0369729
X0125650Y0368650
X0115535Y0335235
X0054400Y0374700
X0081355Y0355873
X0105100Y0309300
X0078900Y0336600
X0076900Y0323000
X0122047Y0372260
X0071906Y0371584
X0111950Y0371200
X0075056Y0362173
X0065607Y0371584
X0058035Y0370100
X0093916Y0352724
X0081355Y0377883
X0133300Y0334100
X0136100Y0334000
X0144700Y0334100
X0144800Y0336700
X0125900Y0337600
X0106852Y0323292
X0139400Y0392460
X0117410Y0381350
X0068757Y0377883
X0081000Y0321900
X0078700Y0340000
X0093916Y0349574
X0092698Y0323224
X0095060Y0327625
X0085500Y0326700
X0068500Y0325100
X0121200Y0359200
X0119200Y0389700
X0137900Y0399500
X0141045Y0355309
X0057400Y0345400
X0071906Y0349574
X0050950Y0318050
X0063000Y0324100
X0052800Y0322400
X0056600Y0324300
X0060225Y0336099
X0099026Y0338368
X0103000Y0323800
X0090766Y0349574
X0132600Y0350090
X0114700Y0351200
X0052765Y0390200
X0142300Y0336700
X0135300Y0399900
X0067900Y0400525
X0062458Y0346425
X0108108Y0395100
X0059500Y0394000
X0090766Y0362173
X0090766Y0374733
X0078206Y0362173
X0078206Y0374733
X0106564Y0346400
X0121175Y0385125
X0125910Y0335006
X0142202Y0334000
X0148600Y0336300
X0124400Y0345300
X0138590Y0345710
X0105755Y0327719
X0133000Y0361500
X0056600Y0320500
X0148316Y0359086
X0052600Y0376600
X0071000Y0394400
X0119200Y0406175
X0082500Y0397600
X0090500Y0397600
X0052900Y0360000
X0141520Y0399700
X0143945Y0354146
X0103365Y0346425
X0115000Y0369500
X0133640Y0390524
X0060561Y0314843
X0075018Y0381033
X0133100Y0358900
X0150293Y0315493
X0135462Y0313727
X0124016Y0313784
X0118009Y0311200
X0118009Y0313810
X0096457Y0323194
X0073000Y0323400
X0079600Y0312000
X0085600Y0335000
X0140300Y0395100
X0086300Y0397600
X0127300Y0392600
X0105000Y0311900
X0124287Y0406262
X0085500Y0323400
X0140700Y0370252
X0097608Y0335534
X0062458Y0390481
X0065607Y0387332
X0065607Y0349574
X0068757Y0384182
X0075056Y0377883
X0075056Y0359023
X0071906Y0355873
X0068757Y0352724
X0081355Y0371584
X0081355Y0365322
X0087617Y0371584
X0087617Y0365322
X0069500Y0308700
X0084126Y0311790
X0097066Y0381033
X0093916Y0377883
X0097066Y0355873
X0093916Y0359023
X0103383Y0349556
X0100215Y0352724
X0100215Y0384182
X0103383Y0387350
X0142500Y0345800
X0082200Y0308700
X0143300Y0396400
X0125174Y0393916
X0141890Y0310570
X0129776Y0374500
X0087617Y0352724
X0099990Y0311200
X0100500Y0328547
X0054660Y0311660
X0089487Y0408435
X0064230Y0303210
X0142702Y0227817
X0138600Y0295900
X0091500Y0267000
X0133000Y0256100
X0124226Y0225194
X0106800Y0262076
X0084016Y0258230
X0119105Y0251511
X0132420Y0273811
X0137196Y0274491
X0061200Y0282600
X0065100Y0282475
X0106100Y0282900
X0068800Y0253300
X0095300Y0247100
X0067700Y0229725
X0074583Y0217314
X0077384Y0253769
X0080270Y0247830
X0071100Y0233575
X0092300Y0282100
X0070453Y0222900
X0112900Y0239200
X0083500Y0266900
X0106600Y0253689
X0110565Y0296331
X0116143Y0230790
X0103580Y0237400
X0051010Y0233570
X0108551Y0294241
X0058900Y0288075
X0075960Y0284049
X0094400Y0307200
X0090923Y0293520
X0120600Y0293471
X0134891Y0225171
X0112200Y0234520
X0080300Y0243700
X0121200Y0234890
X0073011Y0246365
X0123100Y0295974
X0122957Y0300991
X0147500Y0289405
X0127600Y0259700
X0138000Y0244600
X0076200Y0247400
X0077437Y0262760
X0120020Y0254430
X0130167Y0234733
X0076670Y0208772
X0106574Y0280028
X0150293Y0302117
X0115000Y0273700
X0120070Y0273700
X0137083Y0278045
X0128760Y0273701
X0150240Y0277940
X0078770Y0290708
X0068990Y0260465
X0099990Y0307900
X0075870Y0290700
X0065755Y0256045
X0111600Y0262730
X0109800Y0264928
X0107200Y0265000
X0141280Y0256310
X0098720Y0236980
X0077010Y0256645
X0059850Y0235830
X0111600Y0284000
X0072500Y0214000
X0145500Y0227700
X0091300Y0252900
X0142085Y0230549
X0145580Y0248082
X0149215Y0267745
X0149862Y0243788
X0122876Y0245300
X0058823Y0213531
X0134358Y0230069
X0051600Y0241200
X0117840Y0242200
X0078600Y0283970
X0058000Y0217700
X0138100Y0213600
X0145250Y0256890
X0102600Y0267000
X0117400Y0266500
X0128760Y0265726
X0125100Y0273720
X0135315Y0279813
X0111100Y0273700
X0111400Y0254680
X0122876Y0242800
X0132500Y0221900
X0135000Y0221200
X0070900Y0241500
X0075000Y0214000
X0070000Y0280000
X0072700Y0301200
X0097177Y0263320
X0090800Y0258225
X0068990Y0257000
X0077900Y0274700
X0051500Y0258200
X0123790Y0227656
X0123690Y0230156
X0052050Y0208760
X0058654Y0290605
X0111177Y0293471
X0118300Y0237500
X0121720Y0265330
X0128900Y0255898
X0131216Y0280187
X0074000Y0270800
X0076500Y0270700
X0062500Y0272500
X0090900Y0222850
X0097440Y0283590
X0064567Y0306665
X0085672Y0283985
X0065800Y0260875
X0084000Y0261375
X0087500Y0237300
X0103500Y0240619
X0113590Y0245170
X0081600Y0241500
X0063300Y0237600
X0076284Y0280470
X0085600Y0298100
X0057141Y0209341
X0052000Y0230400
X0072000Y0235925
X0065801Y0253145
X0142300Y0216300
X0141954Y0224274
X0146000Y0216350
X0146390Y0224040
X0081864Y0297900
X0082022Y0303350
X0075300Y0305150
X0142780Y0266830
X0100700Y0293600
X0123120Y0213088
X0052410Y0190190
X0061123Y0133070
X0059700Y0196200
X0059945Y0120630
X0052410Y0186900
X0059945Y0117795
X0060800Y0137000
X0135300Y0175100
X0095944Y0149687
X0071124Y0178565
X0074046Y0186490
X0144280Y0195130
X0067486Y0188977
X0089200Y0138800
X0067386Y0191935
X0075284Y0180800
X0052948Y0200700
X0118692Y0137304
X0129810Y0191310
X0149100Y0189963
X0150005Y0184973
X0150619Y0178646
X0126153Y0199079
X0066900Y0125300
X0146882Y0177501
X0137900Y0179160
X0109670Y0136060
X0143742Y0203395
X0147600Y0117000
X0125700Y0183700
X0064050Y0201010
X0108270Y0138630
X0073550Y0166680
X0071370Y0188993
X0071146Y0186489
X0082370Y0197010
X0146300Y0161010
X0089170Y0141540
X0140903Y0199421
X0136190Y0158100
X0124779Y0201633
X0072150Y0204810
X0124338Y0204742
X0120724Y0108937
X0118990Y0131580
X0109200Y0128500
X0120500Y0115525
X0109200Y0118500
X0123325Y0111000
X0109350Y0115501
X0095950Y0152900
X0080788Y0190812
X0144500Y0169570
X0076442Y0166907
X0071600Y0200900
X0133690Y0158100
X0122900Y0170100
X0140830Y0192530
X0068600Y0159160
X0068960Y0173300
X0102999Y0131799
X0072300Y0159400
X0122156Y0157844
X0113000Y0158000
X0126500Y0158000
X0052237Y0129522
X0052876Y0195712
X0100360Y0116500
X0142892Y0136645
X0145185Y0134214
X0147800Y0200789
X0148429Y0147682
X0150155Y0145086
X0149800Y0135100
X0149800Y0138100
X0143980Y0199674
X0143269Y0150456
X0140554Y0171688
X0145296Y0188835
X0140554Y0168887
X0126500Y0174000
X0092500Y0116200
X0089256Y0135056
X0132828Y0138400
X0141220Y0123070
X0143400Y0121700
X0075300Y0183875
X0067330Y0169267
X0148819Y0125697
X0148819Y0123197
X0066830Y0122329
X0086700Y0119100
X0066874Y0130590
X0132500Y0167300
X0115400Y0159500
X0131528Y0114271
X0083520Y0158520
X0086100Y0158390
X0083410Y0161020
X0086100Y0155840
X0086100Y0153340
X0113000Y0160700
X0053267Y0109094
X0116200Y0115100
X0096400Y0137475
X0124500Y0167100
X0142000Y0146000
X0126300Y0176575
X0133500Y0149385
X0067486Y0186414
X0101230Y0127010
X0140869Y0112677
X0140869Y0120551
X0131700Y0131000
X0112000Y0123500
X0126575Y0111416
X0129328Y0122500
X0120626Y0123500
X0105916Y0109952
X0070580Y0167179
X0060411Y0130200
X0067126Y0128100
X0060112Y0113992
X0088500Y0128000
X0068432Y0152147
X0069285Y0132321
X0069195Y0135799
X0071970Y0135893
X0072044Y0132312
X0068434Y0149506
X0068375Y0144100
X0068335Y0141369
X0081800Y0188500
X0059900Y0199900
X0065301Y0187762
X0135000Y0206900
X0119060Y0199695
X0148400Y0155765
X0052155Y0121218
X0134400Y0127652
X0138458Y0146458
X0135500Y0135000
X0081500Y0176515
X0133500Y0146800
X0135500Y0138000
X0117800Y0147200
X0120800Y0147200
X0054200Y0025400
X0059240Y0067242
X0107124Y0071004
X0109121Y0069500
X0106000Y0091900
X0090151Y0068985
X0112600Y0052800
X0125800Y0047330
X0053400Y0102788
X0112800Y0060400
X0056348Y0036210
X0130500Y0074700
X0052120Y0078373
X0104600Y0050501
X0084500Y0066500
X0052502Y0080978
X0107000Y0044500
X0053600Y0044100
X0141100Y0086500
X0142400Y0091300
X0104500Y0073500
X0129500Y0091475
X0111075Y0104600
X0123740Y0079791
X0145100Y0087400
X0131470Y0081260
X0129300Y0082650
X0111000Y0077000
X0102190Y0063225
X0102190Y0066725
X0110950Y0082050
X0063086Y0065762
X0072500Y0066500
X0145000Y0090700
X0140730Y0072600
X0133000Y0059900
X0088000Y0066500
X0116500Y0074000
X0118500Y0075500
X0115000Y0044500
X0055000Y0076000
X0104425Y0082500
X0123710Y0082300
X0053434Y0106562
X0075280Y0075704
X0119000Y0044600
X0098500Y0066500
X0068500Y0066500
X0058976Y0036402
X0126425Y0057000
X0091358Y0083745
X0074757Y0083745
X0091358Y0086745
X0074757Y0086745
X0091358Y0092745
X0074757Y0092745
X0074757Y0089745
X0091358Y0089745
X0065928Y0076500
X0127900Y0045000
X0111000Y0044600
X0086500Y0075000
X0098000Y0075500
X0095400Y0066500
X0091700Y0066500
X0076500Y0066500
X0060000Y0075500
X0057500Y0075500
X0059425Y0053075
X0053000Y0041500
X0100000Y0098500
X0104575Y0067581
X0104575Y0062369
X0146800Y0079000
X0147947Y0009800
X0140869Y0104803
X0141700Y0096929
X0140869Y0089055
X0108727Y0099153
X0116560Y0088651
X0115200Y0098200
X0120726Y0105000
X0122500Y0058000
X0242218Y0003000
X0222218Y0003000
X0202218Y0003000
X0182218Y0003000
X0162218Y0003000
X0129575Y0057375
X0115025Y0104800
X0108800Y0091900
X0119700Y0089200
X0209142Y0053664
X0166200Y0105500
X0201500Y0061000
X0204300Y0060600
X0244208Y0097302
X0250000Y0073000
X0222890Y0101240
X0229900Y0061000
X0211400Y0059238
X0187400Y0101500
X0159923Y0096281
X0163423Y0096281
X0169347Y0096281
X0172847Y0096281
X0227760Y0082524
X0232150Y0082480
X0224330Y0083210
X0240000Y0067400
X0187700Y0099000
X0176300Y0098700
X0156710Y0073420
X0246488Y0105792
X0249988Y0105792
X0158246Y0078872
X0239660Y0091920
X0236648Y0100739
X0204100Y0067400
X0249475Y0055812
X0175700Y0076245
X0178200Y0076145
X0179900Y0091300
X0226040Y0101220
X0232325Y0101230
X0169700Y0102250
X0224000Y0074275
X0216400Y0106400
X0152800Y0075600
X0189400Y0069600
X0193100Y0069100
X0237000Y0047200
X0219900Y0101300
X0221300Y0092100
X0218600Y0092100
X0176900Y0014625
X0240710Y0099570
X0240160Y0107000
X0184800Y0100300
X0181960Y0099260
X0230600Y0091700
X0201900Y0083300
X0234537Y0074638
X0246200Y0074600
X0214306Y0062233
X0233000Y0047100
X0248359Y0046559
X0166500Y0096400
X0198281Y0101286
X0165700Y0011100
X0142218Y0003000
X0122218Y0003000
X0102218Y0003000
X0082218Y0003000
X0062218Y0003000
X0207700Y0059100
X0248700Y0075900
X0250900Y0090900
X0166719Y0075874
X0218600Y0069300
X0215800Y0069300
X0219600Y0074000
X0211800Y0093870
X0230800Y0057613
X0191312Y0084512
X0187272Y0084472
X0190200Y0100500
X0182925Y0084300
X0213100Y0069300
X0245391Y0099589
X0229000Y0101000
X0209500Y0092326
X0239347Y0079457
X0227547Y0074275
X0158873Y0093976
X0164429Y0093991
X0168297Y0093976
X0173853Y0093991
X0237280Y0107510
X0244987Y0103528
X0224958Y0107236
X0209824Y0106122
X0235630Y0104990
X0241300Y0159748
X0152800Y0111600
X0178346Y0159748
X0152500Y0199500
X0181495Y0200655
X0169100Y0113900
X0187794Y0169197
X0244450Y0169197
X0247599Y0166047
X0247637Y0162898
X0178346Y0188095
X0181495Y0169197
X0181495Y0188095
X0171836Y0198300
X0171836Y0200655
X0212727Y0132154
X0178346Y0203805
X0168800Y0126800
X0184645Y0172347
X0189700Y0140400
X0151800Y0116500
X0174436Y0132394
X0206692Y0159748
X0184645Y0169197
X0173000Y0170200
X0169500Y0180200
X0208500Y0126057
X0175196Y0172347
X0238150Y0159748
X0170800Y0193100
X0174336Y0192800
X0184645Y0188095
X0175196Y0197506
X0181495Y0191244
X0178346Y0191244
X0184645Y0191244
X0178346Y0197506
X0239206Y0112300
X0225658Y0153369
X0227700Y0151900
X0171700Y0156900
X0181495Y0197506
X0212991Y0166047
X0178346Y0175496
X0172890Y0153260
X0181495Y0162898
X0170610Y0131900
X0186200Y0125600
X0187794Y0172347
X0206692Y0166047
X0175196Y0203805
X0209842Y0153449
X0175196Y0206955
X0184645Y0203805
X0178346Y0206955
X0181495Y0206955
X0181495Y0203805
X0222402Y0156599
X0225300Y0125200
X0219253Y0156599
X0184729Y0115820
X0235001Y0159748
X0235001Y0162898
X0239900Y0117550
X0219253Y0162898
X0190944Y0169197
X0176000Y0140500
X0187794Y0156599
X0165690Y0149622
X0195983Y0129294
X0200000Y0128764
X0200393Y0166047
X0203542Y0159748
X0204120Y0132294
X0191482Y0129294
X0200393Y0162898
X0161237Y0181735
X0153051Y0187354
X0174569Y0180202
X0190944Y0166047
X0181495Y0184945
X0184645Y0184945
X0162657Y0117297
X0172100Y0146300
X0184645Y0175496
X0223300Y0117400
X0230293Y0117417
X0174600Y0114000
X0181495Y0172347
X0184645Y0200655
X0212991Y0162898
X0184645Y0197506
X0208576Y0128957
X0222402Y0159748
X0242500Y0129000
X0184645Y0178646
X0178284Y0132394
X0161900Y0150500
X0159900Y0155600
X0187794Y0175496
X0184645Y0153449
X0194094Y0166047
X0192400Y0152804
X0187794Y0153449
X0190944Y0159748
X0181495Y0153449
X0190944Y0162898
X0184645Y0159748
X0184645Y0162898
X0187794Y0166047
X0187794Y0162898
X0184645Y0156599
X0232384Y0148884
X0231851Y0159748
X0231851Y0162898
X0231851Y0156599
X0208627Y0132394
X0212727Y0129654
X0221278Y0132294
X0235001Y0153449
X0235001Y0156599
X0238150Y0156599
X0219253Y0159748
X0245310Y0113910
X0176550Y0125210
X0217262Y0132294
X0212757Y0127064
X0209842Y0162898
X0225284Y0129294
X0221278Y0129294
X0222402Y0166047
X0219253Y0169197
X0182865Y0113706
X0245520Y0130600
X0171600Y0114000
X0225552Y0166047
X0225552Y0162898
X0229342Y0129240
X0233511Y0129594
X0219253Y0166047
X0222402Y0162898
X0234500Y0117500
X0229396Y0132294
X0225552Y0159748
X0234900Y0126100
X0174553Y0128728
X0178290Y0128824
X0197243Y0162898
X0194094Y0159748
X0195983Y0132294
X0187435Y0129623
X0197243Y0159748
X0170867Y0128211
X0166733Y0128700
X0194094Y0162898
X0197243Y0166047
X0187069Y0116800
X0182000Y0117200
X0181495Y0181795
X0225284Y0132294
X0217262Y0129294
X0209842Y0166047
X0184645Y0181795
X0190744Y0114456
X0196577Y0141185
X0186891Y0113991
X0199985Y0132294
X0200393Y0159748
X0181495Y0175496
X0242195Y0141003
X0162419Y0131032
X0245500Y0127800
X0228702Y0166047
X0156200Y0111600
X0184645Y0166047
X0162200Y0158200
X0156481Y0155933
X0181495Y0166047
X0159328Y0160847
X0181495Y0156599
X0175196Y0156599
X0181495Y0159748
X0178346Y0156599
X0226887Y0117297
X0228702Y0159748
X0225552Y0169197
X0214547Y0174852
X0172621Y0208300
X0225552Y0181795
X0233511Y0132594
X0208200Y0111760
X0247200Y0117400
X0190944Y0181795
X0190944Y0178646
X0187794Y0184945
X0152556Y0147683
X0156286Y0124903
X0156406Y0129203
X0197243Y0175496
X0200393Y0175496
X0190944Y0175496
X0190944Y0172347
X0153954Y0145086
X0194094Y0169197
X0228702Y0178646
X0187794Y0197506
X0187794Y0200655
X0209842Y0175496
X0206692Y0175496
X0203542Y0175496
X0153200Y0170990
X0161240Y0177820
X0238900Y0114800
X0215294Y0117094
X0211370Y0117000
X0199940Y0117500
X0193096Y0115600
X0190800Y0117200
X0179500Y0116800
X0155530Y0116640
X0166700Y0132360
X0159000Y0135000
X0244450Y0191244
X0228702Y0181795
X0219253Y0188095
X0235001Y0175496
X0235001Y0178646
X0222402Y0178646
X0155325Y0139440
X0154050Y0137100
X0219253Y0203805
X0219253Y0206955
X0222402Y0197506
X0219253Y0197506
X0219253Y0200655
X0222402Y0191244
X0241300Y0188095
X0165381Y0201274
X0190944Y0203805
X0166140Y0205955
X0151940Y0203710
X0212991Y0200655
X0212991Y0197506
X0200393Y0206955
X0209842Y0206955
X0206692Y0206955
X0212991Y0203805
X0203542Y0206955
X0212991Y0184945
X0241300Y0172347
X0241300Y0178646
X0241300Y0175496
X0241300Y0197506
X0241300Y0200655
X0241300Y0184945
X0206692Y0181795
X0190944Y0191244
X0190944Y0188095
X0190944Y0184945
X0190944Y0200655
X0190944Y0197506
X0197243Y0184945
X0228702Y0203805
X0235001Y0169197
X0231851Y0178646
X0238150Y0166047
X0231851Y0166047
X0231851Y0169197
X0231851Y0203805
X0235001Y0203805
X0156467Y0203500
X0235001Y0197506
X0228702Y0200655
X0225552Y0188095
X0225552Y0191244
X0235001Y0191244
X0235001Y0188095
X0244450Y0203805
X0250749Y0184945
X0244450Y0172347
X0244450Y0178646
X0244450Y0200655
X0250749Y0191244
X0244450Y0184945
X0247599Y0178646
X0250749Y0188095
X0250749Y0172347
X0244450Y0175496
X0247599Y0172347
X0244450Y0188095
X0250749Y0178646
X0250749Y0175496
X0244450Y0181795
X0250749Y0181795
X0247599Y0184945
X0250749Y0169197
X0250749Y0197506
X0250749Y0200655
X0247599Y0200655
X0250749Y0206955
X0247599Y0206955
X0250749Y0203805
X0247599Y0191244
X0205598Y0140480
X0182108Y0129094
X0203542Y0162898
X0206692Y0162898
X0211490Y0143700
X0203542Y0166047
X0181495Y0178646
X0244450Y0197506
X0180333Y0114292
X0159700Y0112000
X0187794Y0159748
X0158420Y0116610
X0244450Y0159748
X0238150Y0169197
X0250749Y0159748
X0178346Y0200655
X0247599Y0188095
X0247599Y0175496
X0247599Y0181795
X0187794Y0181795
X0231100Y0125600
X0221500Y0125100
X0203970Y0125500
X0187360Y0132425
X0211200Y0140513
X0203600Y0117000
X0153134Y0178572
X0225552Y0197543
X0228702Y0169197
X0222402Y0169197
X0242800Y0132200
X0242812Y0117501
X0209842Y0197506
X0209842Y0200655
X0203542Y0197506
X0203542Y0200655
X0197243Y0197506
X0197243Y0200655
X0247599Y0197506
X0184645Y0206955
X0197243Y0203805
X0212991Y0206955
X0222402Y0206955
X0235001Y0206955
X0247599Y0203805
X0197243Y0178646
X0200393Y0169197
X0197243Y0156599
X0197243Y0191244
X0200393Y0191244
X0209842Y0184945
X0209842Y0181795
X0206692Y0178646
X0212991Y0181795
X0206692Y0169197
X0212991Y0169197
X0203542Y0169197
X0209842Y0156599
X0206692Y0191244
X0203542Y0191244
X0225552Y0178646
X0225552Y0184945
X0219253Y0178646
X0217697Y0174852
X0225552Y0156599
X0228702Y0191244
X0219290Y0191207
X0235001Y0184945
X0235001Y0166047
X0244450Y0156599
X0241300Y0191244
X0231851Y0191244
X0161240Y0190477
X0161237Y0185815
X0178346Y0184945
X0178346Y0162898
X0178346Y0172347
X0175359Y0153286
X0235001Y0200655
X0206692Y0156599
X0175196Y0159748
X0184000Y0140500
X0182103Y0132294
X0209842Y0169197
X0187794Y0178646
X0238150Y0162898
X0175196Y0200655
X0209842Y0159748
X0231592Y0110500
X0228702Y0162898
X0194094Y0219553
X0206692Y0225852
X0151040Y0237870
X0166300Y0212300
X0235400Y0303800
X0168656Y0275156
X0168710Y0272256
X0219253Y0229002
X0184645Y0213254
X0175300Y0240000
X0157200Y0240000
X0174400Y0251936
X0172400Y0220700
X0181495Y0216403
X0165500Y0236100
X0225275Y0246000
X0162100Y0291600
X0228800Y0305500
X0170561Y0306631
X0191199Y0300200
X0206430Y0298780
X0222833Y0261668
X0168300Y0301100
X0226405Y0266335
X0219290Y0222703
X0219290Y0225852
X0248900Y0304900
X0235038Y0229039
X0249300Y0237600
X0234500Y0293500
X0212991Y0225890
X0222440Y0225852
X0247470Y0269990
X0242870Y0237596
X0239870Y0237596
X0250749Y0235301
X0250749Y0229002
X0241338Y0225890
X0241300Y0229002
X0170550Y0304050
X0185000Y0270700
X0170400Y0214700
X0229220Y0283250
X0173800Y0225400
X0209842Y0222703
X0230000Y0255700
X0181495Y0229002
X0205900Y0266130
X0209842Y0229002
X0222402Y0229002
X0215510Y0253310
X0216800Y0255550
X0238400Y0304200
X0206692Y0222703
X0203542Y0219553
X0222402Y0219553
X0231900Y0272700
X0197853Y0307200
X0212991Y0232151
X0182232Y0296424
X0187794Y0210104
X0225552Y0219553
X0242690Y0255300
X0222440Y0222703
X0212991Y0229002
X0187400Y0255700
X0227232Y0270539
X0225590Y0225852
X0225552Y0229002
X0228739Y0216441
X0174600Y0217800
X0179217Y0278528
X0226500Y0273000
X0184645Y0222703
X0187794Y0222703
X0206692Y0229002
X0184645Y0229002
X0175196Y0229002
X0181495Y0222703
X0184645Y0225852
X0181495Y0225852
X0178346Y0229002
X0167200Y0222600
X0184645Y0219553
X0175196Y0213254
X0175196Y0210104
X0178346Y0210104
X0194567Y0255288
X0203542Y0225852
X0191693Y0236370
X0206692Y0219553
X0206692Y0232151
X0193084Y0257400
X0247637Y0225852
X0219253Y0219553
X0216103Y0219591
X0238531Y0263081
X0242087Y0271427
X0225590Y0222720
X0196443Y0294065
X0215500Y0247111
X0220100Y0237200
X0182435Y0281797
X0206051Y0247911
X0228702Y0229002
X0229630Y0264404
X0233033Y0266483
X0197243Y0222703
X0200393Y0225852
X0172977Y0277000
X0200393Y0232151
X0205590Y0269129
X0203090Y0269229
X0197243Y0232151
X0197243Y0229002
X0213258Y0273265
X0197243Y0225852
X0196100Y0281820
X0196200Y0278200
X0212911Y0293869
X0200393Y0222703
X0203542Y0222703
X0201000Y0262500
X0194094Y0229002
X0171592Y0263312
X0174292Y0263300
X0160973Y0254986
X0164800Y0263300
X0245900Y0305000
X0237730Y0248085
X0192380Y0291900
X0209842Y0232151
X0241263Y0282654
X0203542Y0235301
X0246514Y0296825
X0246514Y0294325
X0197243Y0235301
X0220866Y0272160
X0242940Y0268500
X0209842Y0225852
X0209842Y0213254
X0250288Y0273581
X0214034Y0261482
X0190944Y0222702
X0184200Y0264900
X0180458Y0258825
X0187794Y0229002
X0179846Y0255150
X0158750Y0284949
X0183625Y0273500
X0212991Y0222740
X0216141Y0222703
X0160850Y0301344
X0215100Y0244100
X0219900Y0267100
X0193386Y0269142
X0227316Y0256700
X0221000Y0243000
X0237700Y0257387
X0239298Y0268800
X0228739Y0222703
X0231851Y0229002
X0200680Y0257540
X0231889Y0225890
X0241188Y0279347
X0163500Y0229184
X0181495Y0219553
X0153100Y0234800
X0162200Y0221376
X0200393Y0219553
X0201100Y0265120
X0223646Y0293960
X0190944Y0213254
X0174232Y0304333
X0184645Y0210104
X0195031Y0307182
X0230196Y0267477
X0152400Y0284400
X0204560Y0301130
X0176900Y0270100
X0214400Y0303997
X0192448Y0308314
X0187623Y0297475
X0152500Y0289425
X0223800Y0254800
X0217500Y0264000
X0232300Y0261200
X0205500Y0258300
X0190900Y0271700
X0195370Y0273297
X0203542Y0213254
X0200393Y0213254
X0159643Y0226484
X0162653Y0218843
X0161200Y0233600
X0219359Y0281580
X0219339Y0284138
X0247599Y0232151
X0244450Y0232151
X0228702Y0210104
X0231851Y0210104
X0235001Y0210104
X0227841Y0275773
X0204258Y0286691
X0241300Y0210104
X0153800Y0214900
X0153744Y0217435
X0151900Y0213200
X0219253Y0213254
X0219253Y0210104
X0212991Y0213254
X0162594Y0210085
X0162594Y0212585
X0190944Y0210104
X0174400Y0254736
X0219722Y0286728
X0196240Y0253430
X0250749Y0210104
X0247599Y0210104
X0247599Y0213254
X0250749Y0213254
X0235038Y0222740
X0231889Y0222740
X0231889Y0219591
X0238150Y0222703
X0168392Y0298493
X0209746Y0235397
X0230535Y0244564
X0228739Y0225852
X0235038Y0225890
X0247689Y0247929
X0165013Y0254986
X0156970Y0255000
X0156970Y0263250
X0160590Y0263300
X0163690Y0268610
X0244487Y0229002
X0228800Y0302700
X0155800Y0234700
X0152400Y0293400
X0207220Y0301180
X0185725Y0307320
X0181194Y0294074
X0246200Y0299700
X0250749Y0219553
X0196827Y0240349
X0228739Y0213254
X0166361Y0209794
X0166308Y0225189
X0178346Y0225852
X0178346Y0213254
X0200393Y0210104
X0187794Y0213254
X0174400Y0249136
X0184645Y0232151
X0174079Y0234604
X0189228Y0280655
X0191583Y0261363
X0194094Y0232151
X0198990Y0247811
X0197243Y0219553
X0203542Y0232151
X0212991Y0219553
X0209842Y0210104
X0212991Y0210104
X0203542Y0210104
X0222402Y0213254
X0204207Y0278200
X0205130Y0282000
X0211265Y0267300
X0225441Y0282267
X0223672Y0290735
X0219253Y0232151
X0228702Y0219553
X0238188Y0225852
X0238150Y0219553
X0241300Y0213254
X0235001Y0219553
X0232773Y0269532
X0241300Y0232151
X0231851Y0232151
X0244020Y0235518
X0238630Y0235654
X0250749Y0232151
X0185897Y0249936
X0206200Y0255385
X0161400Y0307600
X0242700Y0306800
X0250749Y0225852
X0250749Y0222703
X0164500Y0266000
X0187794Y0219553
X0187794Y0225852
X0203542Y0229002
X0194094Y0225852
X0200393Y0229002
X0194094Y0222703
X0190944Y0219553
X0233790Y0384490
X0158200Y0381400
X0152500Y0382600
X0165501Y0382800
X0156300Y0376300
X0152100Y0378400
X0200300Y0328800
X0161154Y0376704
X0230445Y0325945
X0169077Y0308677
X0241231Y0407285
X0244790Y0375910
X0230287Y0373100
X0199729Y0314565
X0197711Y0349250
X0195800Y0396780
X0233500Y0343911
X0233500Y0346911
X0233800Y0354300
X0233650Y0359628
X0165500Y0386000
X0233600Y0377300
X0221000Y0352000
X0228230Y0340040
X0182350Y0385634
X0178850Y0385634
X0162550Y0387334
X0159050Y0387334
X0232470Y0382280
X0197400Y0370250
X0197400Y0367600
X0247923Y0319000
X0243010Y0323400
X0220134Y0400780
X0208000Y0373240
X0190050Y0389140
X0151265Y0399500
X0197155Y0314223
X0155452Y0401000
X0194600Y0313300
X0154500Y0387350
X0151695Y0357900
X0177500Y0369100
X0199880Y0402846
X0213200Y0399166
X0214175Y0333740
X0200222Y0398150
X0216405Y0335970
X0222986Y0400323
X0217300Y0322800
X0188546Y0326356
X0187400Y0379400
X0153419Y0341978
X0190965Y0348090
X0223420Y0367080
X0222575Y0387625
X0231689Y0334896
X0243700Y0372730
X0194800Y0341700
X0197775Y0346617
X0194500Y0402600
X0181050Y0332250
X0189054Y0397500
X0164500Y0314800
X0242592Y0330683
X0235000Y0335300
X0247923Y0316400
X0236670Y0394550
X0155000Y0321100
X0236860Y0407300
X0217390Y0401340
X0226100Y0325065
X0226710Y0364815
X0170800Y0317600
X0191843Y0403995
X0190100Y0392270
X0176533Y0314049
X0158467Y0344067
X0208628Y0324665
X0221000Y0343800
X0182700Y0342216
X0158459Y0340898
X0225650Y0337520
X0228800Y0312100
X0183800Y0345400
X0216384Y0312216
X0176563Y0310917
X0197660Y0390870
X0248800Y0385700
X0236688Y0311217
X0191420Y0354710
X0213490Y0373690
X0200000Y0407040
X0231500Y0352500
X0208565Y0404501
X0187300Y0384300
X0197620Y0385425
X0195000Y0373900
X0171098Y0341224
X0190600Y0337900
X0168557Y0341221
X0151320Y0322700
X0162160Y0313560
X0198672Y0318175
X0225867Y0345033
X0240500Y0316575
X0180600Y0360200
X0239750Y0394970
X0220515Y0384900
X0243750Y0369730
X0225700Y0362500
X0224632Y0369825
X0196050Y0358770
X0161300Y0354600
X0227206Y0400100
X0213610Y0308800
X0215600Y0316800
X0173880Y0312430
X0156900Y0385700
X0184118Y0387402
X0177082Y0387402
X0157282Y0389102
X0164318Y0389102
X0169200Y0349400
X0180350Y0368650
X0163800Y0356800
X0241400Y0328100
X0228230Y0390390
X0223160Y0362600
X0190922Y0350990
X0233600Y0371500
X0233468Y0341046
X0182372Y0325961
X0243410Y0381323
X0164790Y0341100
X0216725Y0407650
X0222225Y0407650
X0207750Y0366500
X0208360Y0384890
X0233800Y0390118
X0233300Y0356890
X0172550Y0398690
X0169669Y0399419
X0197450Y0356560
X0191408Y0357451
X0190465Y0344426
X0206150Y0412821
X0240200Y0450650
X0216725Y0442220
X0213225Y0442220
X0221225Y0410150
X0217725Y0410150
X0241436Y0445784
X0190270Y0409962
X0158100Y0442700
X0207278Y0416022
X0217100Y0436100
X0213900Y0436000
X0243375Y0448375
X0160700Y0445550
X0163700Y0422119
X0219250Y0422150
X0246500Y0448500
X0231400Y0452000
X0231400Y0449500
X0240210Y0453400
X0240010Y0456000
X0162100Y0414000
X0197600Y0415400
X0160540Y0416912
X0167865Y0427771
X0172530Y0420950
X0185000Y0451500
X0186300Y0448700
X0184480Y0429370
X0186720Y0432490
X0189838Y0434910
X0189766Y0432050
X0225000Y0433100
X0226830Y0435170
X0235200Y0449100
X0205223Y0422665
X0231250Y0447000
X0199940Y0423700
X0235400Y0451600
X0236221Y0454400
X0239500Y0447750
X0195000Y0422540
X0246700Y0451500
X0190370Y0422490
X0246700Y0454100
X0165500Y0433100
X0167008Y0430718
X0151398Y0449930
X0159396Y0449408
X0157500Y0453390
X0171400Y0450600
X0156101Y0425100
X0152200Y0423100
X0168029Y0456660
X0205200Y0445400
X0198405Y0434800
X0207539Y0408686
X0199000Y0444500
X0236900Y0440565
X0195300Y0432327
X0229900Y0436600
X0191780Y0456700
X0191780Y0453300
X0202513Y0434800
X0249400Y0410300
X0185000Y0456500
X0185000Y0454000
X0185245Y0417500
X0198600Y0426600
X0189762Y0429177
X0172530Y0429470
X0157294Y0435623
X0219050Y0418850
X0153079Y0412000
X0224000Y0449100
X0203180Y0416371
X0165194Y0428688
X0245300Y0445800
X0228200Y0459100
X0215000Y0458600
X0209300Y0457700
X0200000Y0455800
X0222200Y0458700
X0152100Y0425700
X0185875Y0415051
X0182750Y0426750
X0218085Y0444520
X0211865Y0444520
X0200274Y0410960
X0154000Y0414750
X0189600Y0459800
X0160852Y0460118
X0269561Y0456044
X0274619Y0424725
X0275100Y0427682
X0252350Y0412850
X0291703Y0450819
X0291623Y0447747
X0287500Y0416100
X0261100Y0443500
X0277700Y0412580
X0271500Y0418300
X0265130Y0440070
X0281300Y0416200
X0397434Y-0473196
X0394508Y-0469943
X0391993Y-0469943
X0391993Y-0473196
X0394508Y-0473196
X0393299Y-0466903
X0404085Y-0466903
X0402876Y-0473196
X0399950Y-0473181
X0405391Y-0473196
X0405391Y-0469943
X0402876Y-0469943
X0376346Y-0447134
X0373420Y-0443881
X0370905Y-0443881
X0370905Y-0447134
X0373420Y-0447134
X0372211Y-0440841
X0382997Y-0440841
X0381788Y-0447134
X0378862Y-0447119
X0384303Y-0447134
X0384303Y-0443881
X0381788Y-0443881
X0380602Y-0435533
X0374975Y-0435380
X0401690Y-0461595
X0396063Y-0461442
X0400392Y-0464207
X0396992Y-0464207
X0276400Y0431810
X0278900Y0421400
X0283674Y0449975
X0274190Y0408900
X0283715Y0452769
X0269700Y0411379
X0276632Y0439502
X0272999Y0430500
X0379304Y-0438145
X0375904Y-0438145
X0278409Y0433722
X0257810Y0435100
X0261700Y0439700
X0297738Y0455418
X0297738Y0458418
X0297738Y0452418
X0295729Y0459912
X0295729Y0456912
X0295729Y0453912
X0263800Y0430300
X0266727Y0443185
X0267100Y0432900
X0271710Y0449840
X0275138Y0451215
X0283622Y0447155
X0331646Y0466536
X0334112Y0447668
X0314969Y0456527
X0290800Y0438300
X0266300Y0435900
X0271500Y0446800
X0278200Y0408700
X0281300Y0419300
X0265100Y0424000
X0269534Y0459061
X0283707Y0459398
X0277563Y0460028
X0291689Y0459912
X0291689Y0456912
X0291689Y0453912
X0287476Y0396680
X0306200Y0308800
X0303000Y0309200
X0287630Y0389378
X0285191Y0390840
X0308926Y0401900
X0283973Y0382553
X0335708Y0372008
X0335500Y0380000
X0253320Y0323327
X0335475Y0358500
X0257900Y0312100
X0264265Y0315817
X0256124Y0336355
X0261300Y0334100
X0259420Y0340630
X0259420Y0343230
X0347100Y0313700
X0277572Y0351198
X0326200Y0370681
X0326100Y0375717
X0272400Y0392400
X0326375Y0380724
X0277700Y0406100
X0325900Y0365643
X0335475Y0367500
X0296780Y0371500
X0300700Y0341300
X0276660Y0316900
X0345500Y0342690
X0276400Y0370400
X0273100Y0381500
X0283664Y0379236
X0273580Y0354250
X0262310Y0311225
X0277290Y0355820
X0275520Y0357910
X0311925Y0366475
X0265100Y0395100
X0298152Y0393332
X0289939Y0309060
X0290000Y0335600
X0286372Y0326768
X0289600Y0322253
X0290120Y0339370
X0286372Y0320700
X0276145Y0366455
X0273355Y0330001
X0312300Y0340700
X0292700Y0403700
X0314340Y0373296
X0329925Y0356016
X0275700Y0403500
X0265320Y0392290
X0287500Y0376900
X0287761Y0366200
X0295500Y0354920
X0308906Y0362637
X0331500Y0383300
X0271100Y0346575
X0271990Y0362360
X0285860Y0336131
X0322093Y0406500
X0318593Y0406500
X0329093Y0406500
X0325593Y0406500
X0327704Y0323535
X0325007Y0323508
X0327704Y0326035
X0327704Y0328635
X0325007Y0326008
X0325007Y0328608
X0281300Y0308800
X0284614Y0387136
X0309500Y0315000
X0311000Y0320500
X0301500Y0326500
X0334600Y0383300
X0276155Y0329999
X0265922Y0354238
X0296938Y0325700
X0349290Y0337646
X0342604Y0318773
X0276100Y0381500
X0325200Y0383900
X0335500Y0363200
X0335700Y0376400
X0272100Y0396300
X0330900Y0314700
X0315075Y0366500
X0287725Y0363473
X0259420Y0345930
X0276100Y0375900
X0262930Y0325300
X0297399Y0397382
X0298748Y0390118
X0332470Y0394092
X0332470Y0397092
X0314985Y0394639
X0314985Y0397639
X0325320Y0390118
X0308500Y0382100
X0325038Y0356890
X0312226Y0382766
X0314132Y0310178
X0291300Y0315900
X0277500Y0348469
X0299138Y0244513
X0307800Y0259200
X0298840Y0279640
X0317110Y0219140
X0302879Y0279686
X0254355Y0300577
X0262100Y0280700
X0261500Y0290440
X0262700Y0265100
X0253898Y0235301
X0253898Y0229002
X0257048Y0232151
X0253898Y0232151
X0258475Y0254872
X0266200Y0294800
X0257145Y0279700
X0255700Y0260000
X0266600Y0268700
X0252639Y0247885
X0378922Y-0206970
X0381848Y-0210223
X0384363Y-0210223
X0384363Y-0206970
X0381848Y-0206970
X0383057Y-0213263
X0372271Y-0213263
X0373480Y-0206970
X0376406Y-0206985
X0370965Y-0206970
X0370965Y-0210223
X0373480Y-0210223
X0374666Y-0218571
X0380293Y-0218724
X0258100Y0295080
X0302879Y0282487
X0256700Y0263800
X0258000Y0266300
X0251459Y0283542
X0251459Y0286542
X0253100Y0257800
X0253110Y0254909
X0262730Y0267600
X0259500Y0263700
X0311670Y0285160
X0285911Y0279569
X0258000Y0284900
X0266300Y0307500
X0287507Y0301596
X0291000Y0297700
X0287050Y0305850
X0282911Y0279569
X0379364Y-0215959
X0375964Y-0215959
X0258628Y0247600
X0302800Y0286200
X0340612Y0278972
X0281889Y0269899
X0285911Y0269899
X0306500Y0301500
X0339700Y0293000
X0327162Y0278972
X0266250Y0297900
X0286106Y0210587
X0272300Y0251000
X0280082Y0251328
X0276200Y0251500
X0286800Y0251400
X0283974Y0251372
X0269016Y0266991
X0267100Y0265000
X0284357Y0264027
X0284357Y0267027
X0280030Y0264098
X0280030Y0267098
X0291500Y0285170
X0291500Y0287670
X0336461Y0283202
X0312272Y0282107
X0314307Y0213737
X0286105Y0213721
X0314307Y0210587
X0295410Y0210587
X0301120Y0238765
X0337467Y0236984
X0309521Y0238741
X0334724Y0235280
X0334724Y0238669
X0326323Y0238693
X0326323Y0235304
X0317922Y0235328
X0317922Y0238717
X0309521Y0235352
X0301120Y0235626
X0268339Y0222126
X0282483Y0235254
X0279983Y0235254
X0288086Y0234844
X0290586Y0234844
X0310449Y0218617
X0304987Y0219503
X0307487Y0219503
X0296734Y0216079
X0307600Y0252300
X0305000Y0252400
X0320931Y0215387
X0320937Y0212839
X0326731Y0213648
X0321045Y0210257
X0326733Y0209885
X0267080Y0214593
X0305002Y0210587
X0263580Y0214593
X0308008Y0210731
X0311158Y0210587
X0253898Y0213254
X0292404Y0213737
X0292404Y0210587
X0257048Y0213254
X0298714Y0210477
X0304000Y0305000
X0266200Y0300500
X0307500Y0256500
X0339700Y0295900
X0336312Y0286352
X0253388Y0273655
X0257048Y0235301
X0257048Y0219553
X0257048Y0225890
X0286000Y0242100
X0289254Y0210587
X0289254Y0213737
X0261269Y0214657
X0269391Y0214593
X0302687Y0275497
X0301120Y0226421
X0301120Y0229810
X0303940Y0212664
X0281889Y0287636
X0309521Y0226397
X0309521Y0229786
X0317922Y0226373
X0317922Y0229762
X0311158Y0213737
X0308460Y0214178
X0303077Y0297519
X0337004Y0210113
X0326323Y0226349
X0326323Y0229738
X0334723Y0229738
X0334723Y0226349
X0314170Y0307020
X0314180Y0299440
X0314201Y0302361
X0314820Y0296128
X0317430Y0295665
X0312315Y0293207
X0315810Y0293450
X0317670Y0291430
X0312114Y0288439
X0309700Y0294789
X0287755Y0287538
X0253898Y0222703
X0253898Y0219553
X0251354Y0152877
X0295075Y0119100
X0288280Y0126212
X0300500Y0125000
X0290200Y0129500
X0301000Y0121016
X0307400Y0122300
X0301000Y0129900
X0307560Y0128500
X0298975Y0118900
X0294800Y0111800
X0315100Y0116400
X0304000Y0116500
X0313800Y0124300
X0318000Y0117200
X0280400Y0126000
X0320938Y0122677
X0321600Y0142100
X0400038Y-0112032
X0402964Y-0115285
X0405479Y-0115285
X0405479Y-0112032
X0402964Y-0112032
X0404173Y-0118325
X0393387Y-0118325
X0394596Y-0112032
X0397522Y-0112047
X0392081Y-0112032
X0392081Y-0115285
X0394596Y-0115285
X0376318Y-0168862
X0373392Y-0165609
X0370877Y-0165609
X0370877Y-0168862
X0373392Y-0168862
X0372183Y-0162569
X0382969Y-0162569
X0381760Y-0168862
X0378834Y-0168847
X0384275Y-0168862
X0384275Y-0165609
X0381760Y-0165609
X0374947Y-0157108
X0380574Y-0157261
X0395782Y-0123633
X0401409Y-0123786
X0400480Y-0121021
X0397080Y-0121021
X0260388Y0125001
X0260200Y0132395
X0274200Y0109500
X0285250Y0117250
X0379276Y-0159873
X0375876Y-0159873
X0253100Y0119900
X0320765Y0114582
X0288116Y0120306
X0287796Y0131542
X0314307Y0197989
X0314930Y0174439
X0292260Y0163487
X0258500Y0146400
X0331741Y0125796
X0273450Y0125050
X0275960Y0126010
X0269493Y0138604
X0339908Y0112609
X0324023Y0115643
X0324023Y0121943
X0324011Y0118843
X0339908Y0108593
X0271300Y0132900
X0269561Y0130987
X0283500Y0126000
X0315900Y0125900
X0271602Y0121400
X0314930Y0168140
X0331641Y0141743
X0331741Y0138243
X0328087Y0141608
X0269004Y0141950
X0269004Y0144450
X0283399Y0153542
X0285899Y0153542
X0268442Y0150799
X0265942Y0150799
X0265942Y0153299
X0268442Y0153299
X0265226Y0164982
X0269133Y0164982
X0314307Y0204288
X0286105Y0204288
X0314307Y0194839
X0311158Y0197989
X0308008Y0194839
X0311158Y0188540
X0314307Y0185534
X0289254Y0197989
X0289254Y0185534
X0286105Y0194839
X0286105Y0185534
X0314930Y0180738
X0289111Y0179235
X0331405Y0167411
X0339939Y0162911
X0339800Y0182926
X0337400Y0193449
X0339812Y0173380
X0320054Y0198663
X0320054Y0195163
X0331405Y0172411
X0314307Y0163487
X0285482Y0168102
X0279457Y0171318
X0339369Y0151952
X0329005Y0152657
X0323509Y0153377
X0317936Y0143897
X0313936Y0143897
X0309936Y0143897
X0305936Y0143897
X0301936Y0143897
X0292204Y0142610
X0287555Y0142419
X0283616Y0150971
X0280616Y0150971
X0298005Y0146118
X0298005Y0148618
X0298005Y0151118
X0326733Y0201485
X0326932Y0205685
X0286105Y0176085
X0314307Y0201139
X0282975Y0172975
X0292260Y0179235
X0308152Y0179235
X0271209Y0177524
X0295411Y0185534
X0289254Y0201139
X0308008Y0198133
X0305002Y0179235
X0331405Y0154911
X0253898Y0175496
X0308008Y0185391
X0264222Y0176791
X0308152Y0182385
X0267722Y0176791
X0289254Y0182385
X0331405Y0189911
X0308152Y0176085
X0289254Y0176085
X0331405Y0182926
X0308152Y0172936
X0292384Y0172936
X0273644Y0174267
X0295410Y0179235
X0257048Y0191244
X0331405Y0169911
X0308008Y0166637
X0292260Y0169643
X0331405Y0174911
X0311158Y0169643
X0264118Y0188095
X0289254Y0172792
X0331405Y0179911
X0308152Y0169786
X0270472Y0188488
X0295410Y0172936
X0305002Y0172936
X0331405Y0159911
X0305002Y0169786
X0331405Y0164911
X0311158Y0163487
X0305002Y0176085
X0257048Y0172347
X0289110Y0163487
X0292404Y0176085
X0253898Y0169197
X0295410Y0169786
X0295410Y0194839
X0262580Y0207262
X0292404Y0194983
X0266080Y0207262
X0308008Y0188540
X0253898Y0197506
X0292404Y0185534
X0311158Y0191690
X0257048Y0197506
X0257048Y0200655
X0289254Y0191690
X0308008Y0191690
X0257048Y0206955
X0292404Y0191690
X0299667Y0201334
X0305002Y0204432
X0292404Y0201282
X0308152Y0204432
X0308008Y0207438
X0289254Y0194839
X0314930Y0177588
X0314930Y0171289
X0255492Y0152905
X0301151Y0108649
X0307500Y0125635
X0294200Y0128800
X0279200Y0114100
X0283248Y0142046
X0280744Y0142070
X0263030Y0150846
X0263294Y0153366
X0323384Y0161378
X0323384Y0165378
X0320239Y0151075
X0337083Y0197000
X0268435Y0121476
X0252374Y0132159
X0292361Y0197970
X0319601Y0201140
X0311158Y0194839
X0311158Y0201139
X0297372Y0196616
X0301507Y0195435
X0286105Y0197989
X0286105Y0201139
X0253898Y0200655
X0260269Y0207358
X0253898Y0206955
X0289091Y0204331
X0268391Y0207262
X0314307Y0207438
X0311158Y0204288
X0337004Y0206113
X0337004Y0202113
X0331881Y0108593
X0331881Y0112608
X0279600Y0131400
X0321349Y0130044
X0321276Y0134532
X0329297Y0129890
X0329297Y0134594
X0253898Y0178646
X0253898Y0184945
X0253898Y0172347
X0253898Y0191244
X0262880Y0178977
X0274500Y0131629
X0290889Y0152318
X0268510Y0179088
X0285482Y0190187
X0286105Y0182385
X0286105Y0172936
X0278155Y0176085
X0285980Y0163487
X0293693Y0152232
X0304436Y0135897
X0301936Y0135797
X0314307Y0191690
X0311301Y0182385
X0311158Y0185534
X0308008Y0163487
X0331405Y0192411
X0331405Y0187411
X0331405Y0177411
X0323384Y0177378
X0323384Y0173378
X0331405Y0157411
X0323384Y0169378
X0323384Y0157378
X0333278Y0151129
X0339800Y0189911
X0339800Y0179911
X0339800Y0185911
X0339800Y0176911
X0339800Y0165911
X0339800Y0169911
X0339800Y0159911
X0339800Y0154911
X0337842Y0128533
X0339101Y0121128
X0339101Y0117328
X0268500Y0045500
X0260050Y0087026
X0267939Y0041122
X0279934Y0051688
X0297466Y0051521
X0286000Y0047000
X0342180Y0106900
X0342200Y0100500
X0320500Y0100400
X0264989Y0101732
X0280910Y0102880
X0282505Y0083545
X0277505Y0083545
X0272505Y0083545
X0256000Y0056000
X0275386Y0102710
X0293773Y0073530
X0297575Y0073738
X0298575Y0101900
X0294600Y0106900
X0339900Y0066000
X0253000Y0077500
X0283500Y0089500
X0403643Y-0067750
X0402550Y-0070790
X0405050Y-0070790
X0402550Y-0074043
X0405050Y-0074043
X0414143Y-0067750
X0408050Y-0074028
X0410550Y-0074043
X0413050Y-0070790
X0413050Y-0074043
X0415550Y-0074043
X0415550Y-0070790
X0396950Y-0074043
X0394450Y-0070790
X0391950Y-0070790
X0391950Y-0074043
X0394450Y-0074043
X0393357Y-0067750
X0399450Y-0074028
X0255213Y0106099
X0258713Y0106099
X0287578Y0084092
X0274760Y0105140
X0263102Y0091725
X0259894Y0090072
X0276400Y0092300
X0260970Y0098600
X0265801Y0106040
X0251200Y0093800
X0273400Y0092800
X0251900Y0100100
X0256900Y0087300
X0278300Y0095019
X0257800Y0082800
X0321800Y0060055
X0290000Y0082000
X0274500Y0058000
X0277000Y0051665
X0290000Y0067975
X0300425Y0054516
X0300070Y0084000
X0309570Y0084000
X0339908Y0104577
X0316066Y0108407
X0252925Y0054000
X0255000Y0082700
X0339900Y0069100
X0316025Y0060200
X0279800Y0072700
X0259000Y0047500
X0274219Y0051641
X0260970Y0042441
X0277000Y0041982
X0286000Y0067975
X0282440Y0051941
X0303575Y0054516
X0290245Y0046978
X0295402Y0048051
X0288856Y0012166
X0267022Y0012166
X0269095Y0034625
X0255750Y0077350
X0342900Y0066100
X0274400Y0090019
X0313977Y0033400
X0300600Y0010591
X0337375Y0076600
X0319175Y0060200
X0322600Y0076100
X0268675Y0074400
X0259500Y0101100
X0252300Y0107664
X0260132Y0093768
X0267168Y0093768
X0251113Y0102919
X0254397Y0103697
X0259759Y0103651
X0300856Y0104059
X0331881Y0104577
X0322500Y0102900
X0378922Y0021302
X0381848Y0018049
X0384363Y0018049
X0384363Y0021302
X0381848Y0021302
X0383057Y0015009
X0372271Y0015009
X0373480Y0021302
X0376406Y0021287
X0370965Y0021302
X0370965Y0018049
X0373480Y0018049
X0376346Y0059410
X0373420Y0062663
X0370905Y0062663
X0370905Y0059410
X0373420Y0059410
X0372211Y0065703
X0382997Y0065703
X0381788Y0059410
X0378862Y0059425
X0384303Y0059410
X0384303Y0062663
X0381788Y0062663
X0374666Y0009701
X0380293Y0009548
X0374975Y0071164
X0380602Y0071011
X0375904Y0068399
X0379304Y0068399
X0379364Y0012313
X0375964Y0012313
X0351331Y0100788
X0351331Y0080788
X0351331Y0060788
X0351331Y0040788
X0351331Y0020788
X0342218Y0003000
X0322218Y0003000
X0302218Y0003000
X0282218Y0003000
X0262218Y0003000
X0351331Y0200788
X0351331Y0180788
X0351331Y0160788
X0351331Y0140788
X0351331Y0120788
X0403857Y0211066
X0404950Y0214106
X0402450Y0214106
X0404950Y0217359
X0402450Y0217359
X0403643Y0261522
X0402550Y0258482
X0405050Y0258482
X0402550Y0255229
X0405050Y0255229
X0414143Y0261522
X0408050Y0255244
X0410550Y0255229
X0413050Y0258482
X0413050Y0255229
X0415550Y0255229
X0415550Y0258482
X0393357Y0261522
X0399450Y0255244
X0396950Y0255229
X0394450Y0258482
X0394450Y0255229
X0391950Y0255229
X0391950Y0258482
X0393357Y0211066
X0399450Y0217344
X0396950Y0217359
X0394450Y0214106
X0394450Y0217359
X0391950Y0217359
X0391950Y0214106
X0414143Y0211066
X0408050Y0217344
X0410550Y0217359
X0413050Y0214106
X0413050Y0217359
X0415550Y0217359
X0415550Y0214106
X0351331Y0300788
X0351331Y0280788
X0351331Y0260788
X0351331Y0240788
X0351331Y0220788
X0383057Y0384281
X0384363Y0387321
X0384363Y0390574
X0381848Y0387321
X0381848Y0390574
X0370965Y0390574
X0370965Y0387321
X0373480Y0390574
X0373480Y0387321
X0376406Y0390559
X0378922Y0390574
X0372271Y0384281
X0374666Y0378973
X0380293Y0378820
X0375964Y0381585
X0379364Y0381585
X0351331Y0397531
X0351331Y0377531
X0351331Y0357531
X0403857Y0409338
X0404950Y0412378
X0402450Y0412378
X0404950Y0415631
X0402450Y0415631
X0393357Y0409338
X0399450Y0415616
X0396950Y0415631
X0394450Y0412378
X0394450Y0415631
X0391950Y0415631
X0391950Y0412378
X0414143Y0409338
X0408050Y0415616
X0410550Y0415631
X0413050Y0412378
X0413050Y0415631
X0415550Y0415631
X0415550Y0412378
X0351331Y0437531
X0351331Y0417531
M00
X0184733Y0058583
X0176859Y0058583
X0168985Y0058583
X0161111Y0058583
X0153237Y0058583
X0155205Y0052677
X0165048Y0052677
X0172922Y0052677
X0182764Y0052677
M00
X0117047Y0024764
X0127047Y0024764
M00
X0090472Y0024764
X0100472Y0024764
X0063898Y0024764
X0073898Y0024764
X0237717Y0024764
X0247717Y0024764
X0211142Y0024764
X0221142Y0024764
M00
X0023819Y0399154
X0023819Y0389154
X0023819Y0379154
X0023819Y0369154
X0023819Y0359154
X0023819Y0349154
X0023819Y0339154
X0023819Y0409154
X0065709Y0042244
X0075709Y0042244
X0085709Y0042244
X0095709Y0042244
X0065709Y0052244
X0075709Y0052244
X0085709Y0052244
X0095709Y0052244
M00
X-0051000Y0382816
X-0061000Y0382816
X-0056000Y0396000
X-0051100Y0250316
X-0061100Y0250316
X-0056100Y0263500
X-0051709Y0056192
X-0061709Y0056192
X-0056709Y0043008
X-0025000Y0056184
X-0035000Y0056184
X-0030000Y0043000
X-0035100Y0250316
X-0025100Y0250316
X-0030100Y0263500
X-0026000Y0418816
X-0036000Y0418816
X-0031000Y0432000
M00
X0143118Y0044803
X0194851Y0044803
M00
X0024016Y0089331
X0330315Y0089331
M00
X0022047Y0046417
X0333466Y0046417
M00
X0236220Y0424016
X0301181Y0424016
M00
X0105316Y0213343
M00
X0017716Y0018465
X0045276Y0018465
X0264173Y0020040
X0291733Y0020040
X0309055Y0018465
X0336615Y0018465
M00
X0403692Y-0456375
X0393692Y-0456375
X0403692Y-0481375
X0393692Y-0481375
X0382604Y-0430313
X0372604Y-0430313
X0382604Y-0455313
X0372604Y-0455313
X0372664Y-0223791
X0382664Y-0223791
X0372664Y-0198791
X0382664Y-0198791
X0393780Y-0128853
X0403780Y-0128853
X0393780Y-0103853
X0403780Y-0103853
X0372576Y-0152041
X0382576Y-0152041
X0372576Y-0177041
X0382576Y-0177041
X0403750Y-0057222
X0393750Y-0057222
X0403750Y-0082222
X0393750Y-0082222
X0403750Y-0057222
X0413750Y-0057222
X0403750Y-0082222
X0413750Y-0082222
X0382664Y0004481
X0372664Y0004481
X0372604Y0076231
X0382604Y0076231
X0372604Y0051231
X0382604Y0051231
X0382664Y0029481
X0372664Y0029481
X0393750Y0200538
X0403750Y0200538
X0413750Y0200538
X0403750Y0200538
X0393750Y0272050
X0403750Y0272050
X0393750Y0247050
X0403750Y0247050
X0393750Y0225538
X0403750Y0225538
X0413750Y0225538
X0403750Y0225538
X0413750Y0272050
X0403750Y0272050
X0413750Y0247050
X0403750Y0247050
X0382664Y0373753
X0372664Y0373753
X0382664Y0398753
X0372664Y0398753
X0403750Y0398810
X0413750Y0398810
X0403750Y0398810
X0393750Y0398810
X0403750Y0423810
X0413750Y0423810
X0403750Y0423810
X0393750Y0423810
M00
X0065945Y0297776
M00
X0144685Y0297776
M00
X0027300Y0068200
X0340639Y0432809
M30
